(kicad_pcb
	(version 20260206)
	(generator "pcbnew")
	(generator_version "10.0")
	(general
		(thickness 1.6)
		(legacy_teardrops no)
	)
	(paper "A4")
	(title_block
		(title "01162023_DA0F0TEBIF0_F0T_Expander_BD_F_brd_V02_OCP.brd")
		(comment 1 "Grand Teton / footprints 3793-3798 of 9728")
	)
	(layers
		(0 "F.Cu" signal "TOP")
		(4 "In1.Cu" signal "GND")
		(6 "In2.Cu" signal "VCC")
		(8 "In3.Cu" signal "VCC1")
		(10 "In4.Cu" signal "GND1")
		(12 "In5.Cu" signal "IN1")
		(14 "In6.Cu" signal "GND2")
		(16 "In7.Cu" signal "IN2")
		(18 "In8.Cu" signal "GND3")
		(20 "In9.Cu" signal "IN3")
		(22 "In10.Cu" signal "GND4")
		(24 "In11.Cu" signal "IN4")
		(26 "In12.Cu" signal "GND5")
		(28 "In13.Cu" signal "IN5")
		(30 "In14.Cu" signal "GND6")
		(32 "In15.Cu" signal "IN6")
		(34 "In16.Cu" signal "GND7")
		(2 "B.Cu" signal "BOTTOM")
		(9 "F.Adhes" user "F.Adhesive")
		(11 "B.Adhes" user "B.Adhesive")
		(13 "F.Paste" user "Package Geometry/Pastemask Top")
		(15 "B.Paste" user "Package Geometry/Pastemask Bottom")
		(5 "F.SilkS" user "Ref Des/Silkscreen Top")
		(7 "B.SilkS" user "Ref Des/Silkscreen Bottom")
		(1 "F.Mask" user "Board Geometry/Soldermask Top")
		(3 "B.Mask" user "Board Geometry/Soldermask Bottom")
		(17 "Dwgs.User" user "User.Drawings")
		(19 "Cmts.User" user "User.Comments")
		(21 "Eco1.User" user "User.Eco1")
		(23 "Eco2.User" user "User.Eco2")
		(25 "Edge.Cuts" user "Board Geometry/Outline")
		(27 "Margin" user)
		(31 "F.CrtYd" user "Package Geometry/Place Bound Top")
		(29 "B.CrtYd" user "Package Geometry/Place Bound Bottom")
		(35 "F.Fab" user "Ref Des/Assembly Top")
		(33 "B.Fab" user "Ref Des/Assembly Bottom")
	)
	(footprint ""
		(layer "F.Cu")
		(at 301.992284 -32.739584 180)
		(property "Reference" "C505"
			(at 0 0 180)
			(layer "F.SilkS")
			(hide yes)
			(effects
				(font
					(size 1.27 1.27)
				)
			)
		)
		(property "Value" ""
			(at 0 0 180)
			(layer "F.Fab")
			(effects
				(font
					(size 1.27 1.27)
				)
			)
		)
		(duplicate_pad_numbers_are_jumpers no)
		(fp_line
			(start 0.299974 0.150114)
			(end -0.299974 0.150114)
			(stroke
				(width 0.1)
				(type default)
			)
			(layer "F.Fab")
		)
		(fp_line
			(start 0.299974 -0.150114)
			(end 0.299974 0.150114)
			(stroke
				(width 0.1)
				(type default)
			)
			(layer "F.Fab")
		)
		(fp_line
			(start -0.299974 0.150114)
			(end -0.299974 -0.150114)
			(stroke
				(width 0.1)
				(type default)
			)
			(layer "F.Fab")
		)
		(fp_line
			(start -0.299974 -0.150114)
			(end 0.299974 -0.150114)
			(stroke
				(width 0.1)
				(type default)
			)
			(layer "F.Fab")
		)
		(pad "1" smd rect
			(at -0.2667 0 180)
			(size 0.3048 0.381)
			(layers "F.Cu" "F.Mask" "F.Paste")
			(net "P5E_PEX2_STN2_TX_DP<38>")
		)
		(pad "2" smd rect
			(at 0.2667 0 180)
			(size 0.3048 0.381)
			(layers "F.Cu" "F.Mask" "F.Paste")
			(net "P5E_PEX2_STN2_TX_C_DP<38>")
		)
	)
	(footprint ""
		(layer "F.Cu")
		(at 168.343834 -44.87291)
		(property "Reference" "R561"
			(at 0 0 0)
			(layer "F.SilkS")
			(hide yes)
			(effects
				(font
					(size 1.27 1.27)
				)
			)
		)
		(property "Value" ""
			(at 0 0 0)
			(layer "F.Fab")
			(effects
				(font
					(size 1.27 1.27)
				)
			)
		)
		(duplicate_pad_numbers_are_jumpers no)
		(fp_line
			(start -0.7874 -0.4064)
			(end 0.7874 -0.4064)
			(stroke
				(width 0.1524)
				(type default)
			)
			(layer "F.SilkS")
		)
		(fp_line
			(start -0.7874 0.4064)
			(end -0.7874 -0.4064)
			(stroke
				(width 0.1524)
				(type default)
			)
			(layer "F.SilkS")
		)
		(fp_line
			(start 0.7874 -0.4064)
			(end 0.7874 0.4064)
			(stroke
				(width 0.1524)
				(type default)
			)
			(layer "F.SilkS")
		)
		(fp_line
			(start 0.7874 0.4064)
			(end -0.7874 0.4064)
			(stroke
				(width 0.1524)
				(type default)
			)
			(layer "F.SilkS")
		)
		(fp_line
			(start -0.67945 -0.305054)
			(end -0.12065 -0.305054)
			(stroke
				(width 0.1)
				(type default)
			)
			(layer "F.Fab")
		)
		(fp_line
			(start -0.67945 0.3048)
			(end -0.67945 -0.305054)
			(stroke
				(width 0.1)
				(type default)
			)
			(layer "F.Fab")
		)
		(fp_line
			(start -0.12065 -0.305054)
			(end -0.12065 -0.2794)
			(stroke
				(width 0.1)
				(type default)
			)
			(layer "F.Fab")
		)
		(fp_line
			(start -0.12065 -0.2794)
			(end 0.12065 -0.2794)
			(stroke
				(width 0.1)
				(type default)
			)
			(layer "F.Fab")
		)
		(fp_line
			(start -0.12065 0.2794)
			(end -0.12065 0.3048)
			(stroke
				(width 0.1)
				(type default)
			)
			(layer "F.Fab")
		)
		(fp_line
			(start -0.12065 0.3048)
			(end -0.67945 0.3048)
			(stroke
				(width 0.1)
				(type default)
			)
			(layer "F.Fab")
		)
		(fp_line
			(start 0.120396 0.2794)
			(end -0.12065 0.2794)
			(stroke
				(width 0.1)
				(type default)
			)
			(layer "F.Fab")
		)
		(fp_line
			(start 0.120396 0.3048)
			(end 0.120396 0.2794)
			(stroke
				(width 0.1)
				(type default)
			)
			(layer "F.Fab")
		)
		(fp_line
			(start 0.12065 -0.3048)
			(end 0.67945 -0.3048)
			(stroke
				(width 0.1)
				(type default)
			)
			(layer "F.Fab")
		)
		(fp_line
			(start 0.12065 -0.2794)
			(end 0.12065 -0.3048)
			(stroke
				(width 0.1)
				(type default)
			)
			(layer "F.Fab")
		)
		(fp_line
			(start 0.67945 -0.3048)
			(end 0.67945 0.3048)
			(stroke
				(width 0.1)
				(type default)
			)
			(layer "F.Fab")
		)
		(fp_line
			(start 0.67945 0.3048)
			(end 0.120396 0.3048)
			(stroke
				(width 0.1)
				(type default)
			)
			(layer "F.Fab")
		)
		(pad "1" smd circle
			(at -0.40005 0)
			(size 0 0)
			(layers "F.Cu" "F.Mask" "F.Paste")
			(net "SSD5_ADC_A0")
		)
		(pad "2" smd circle
			(at 0.40005 0)
			(size 0 0)
			(layers "F.Cu" "F.Mask" "F.Paste")
			(net "P3V3_AUX")
		)
	)
	(footprint ""
		(layer "F.Cu")
		(at 249.391678 -152.71115 90)
		(property "Reference" "R724"
			(at 0 0 90)
			(layer "F.SilkS")
			(hide yes)
			(effects
				(font
					(size 1.27 1.27)
				)
			)
		)
		(property "Value" ""
			(at 0 0 90)
			(layer "F.Fab")
			(effects
				(font
					(size 1.27 1.27)
				)
			)
		)
		(duplicate_pad_numbers_are_jumpers no)
		(fp_line
			(start 0.7874 -0.4064)
			(end 0.7874 0.4064)
			(stroke
				(width 0.1524)
				(type default)
			)
			(layer "F.SilkS")
		)
		(fp_line
			(start -0.7874 -0.4064)
			(end 0.7874 -0.4064)
			(stroke
				(width 0.1524)
				(type default)
			)
			(layer "F.SilkS")
		)
		(fp_line
			(start 0.7874 0.4064)
			(end -0.7874 0.4064)
			(stroke
				(width 0.1524)
				(type default)
			)
			(layer "F.SilkS")
		)
		(fp_line
			(start -0.7874 0.4064)
			(end -0.7874 -0.4064)
			(stroke
				(width 0.1524)
				(type default)
			)
			(layer "F.SilkS")
		)
		(fp_line
			(start -0.12065 -0.305054)
			(end -0.12065 -0.2794)
			(stroke
				(width 0.1)
				(type default)
			)
			(layer "F.Fab")
		)
		(fp_line
			(start -0.67945 -0.305054)
			(end -0.12065 -0.305054)
			(stroke
				(width 0.1)
				(type default)
			)
			(layer "F.Fab")
		)
		(fp_line
			(start 0.67945 -0.3048)
			(end 0.67945 0.3048)
			(stroke
				(width 0.1)
				(type default)
			)
			(layer "F.Fab")
		)
		(fp_line
			(start 0.12065 -0.3048)
			(end 0.67945 -0.3048)
			(stroke
				(width 0.1)
				(type default)
			)
			(layer "F.Fab")
		)
		(fp_line
			(start 0.12065 -0.2794)
			(end 0.12065 -0.3048)
			(stroke
				(width 0.1)
				(type default)
			)
			(layer "F.Fab")
		)
		(fp_line
			(start -0.12065 -0.2794)
			(end 0.12065 -0.2794)
			(stroke
				(width 0.1)
				(type default)
			)
			(layer "F.Fab")
		)
		(fp_line
			(start 0.120396 0.2794)
			(end -0.12065 0.2794)
			(stroke
				(width 0.1)
				(type default)
			)
			(layer "F.Fab")
		)
		(fp_line
			(start -0.12065 0.2794)
			(end -0.12065 0.3048)
			(stroke
				(width 0.1)
				(type default)
			)
			(layer "F.Fab")
		)
		(fp_line
			(start 0.67945 0.3048)
			(end 0.120396 0.3048)
			(stroke
				(width 0.1)
				(type default)
			)
			(layer "F.Fab")
		)
		(fp_line
			(start 0.120396 0.3048)
			(end 0.120396 0.2794)
			(stroke
				(width 0.1)
				(type default)
			)
			(layer "F.Fab")
		)
		(fp_line
			(start -0.12065 0.3048)
			(end -0.67945 0.3048)
			(stroke
				(width 0.1)
				(type default)
			)
			(layer "F.Fab")
		)
		(fp_line
			(start -0.67945 0.3048)
			(end -0.67945 -0.305054)
			(stroke
				(width 0.1)
				(type default)
			)
			(layer "F.Fab")
		)
		(pad "1" smd circle
			(at -0.40005 0 90)
			(size 0 0)
			(layers "F.Cu" "F.Mask" "F.Paste")
			(net "P3V3_AUX")
		)
		(pad "2" smd circle
			(at 0.40005 0 90)
			(size 0 0)
			(layers "F.Cu" "F.Mask" "F.Paste")
			(net "NIC_ADC_ALERT_N")
		)
	)
	(footprint ""
		(layer "F.Cu")
		(at 193.916808 -410.296868 -90)
		(property "Reference" "R499"
			(at 0 0 270)
			(layer "F.SilkS")
			(hide yes)
			(effects
				(font
					(size 1.27 1.27)
				)
			)
		)
		(property "Value" ""
			(at 0 0 270)
			(layer "F.Fab")
			(effects
				(font
					(size 1.27 1.27)
				)
			)
		)
		(duplicate_pad_numbers_are_jumpers no)
		(fp_line
			(start -0.7874 0.4064)
			(end -0.7874 -0.4064)
			(stroke
				(width 0.1524)
				(type default)
			)
			(layer "F.SilkS")
		)
		(fp_line
			(start 0.7874 0.4064)
			(end -0.7874 0.4064)
			(stroke
				(width 0.1524)
				(type default)
			)
			(layer "F.SilkS")
		)
		(fp_line
			(start -0.7874 -0.4064)
			(end 0.7874 -0.4064)
			(stroke
				(width 0.1524)
				(type default)
			)
			(layer "F.SilkS")
		)
		(fp_line
			(start 0.7874 -0.4064)
			(end 0.7874 0.4064)
			(stroke
				(width 0.1524)
				(type default)
			)
			(layer "F.SilkS")
		)
		(fp_line
			(start -0.67945 0.3048)
			(end -0.67945 -0.305054)
			(stroke
				(width 0.1)
				(type default)
			)
			(layer "F.Fab")
		)
		(fp_line
			(start -0.12065 0.3048)
			(end -0.67945 0.3048)
			(stroke
				(width 0.1)
				(type default)
			)
			(layer "F.Fab")
		)
		(fp_line
			(start 0.120396 0.3048)
			(end 0.120396 0.2794)
			(stroke
				(width 0.1)
				(type default)
			)
			(layer "F.Fab")
		)
		(fp_line
			(start 0.67945 0.3048)
			(end 0.120396 0.3048)
			(stroke
				(width 0.1)
				(type default)
			)
			(layer "F.Fab")
		)
		(fp_line
			(start -0.12065 0.2794)
			(end -0.12065 0.3048)
			(stroke
				(width 0.1)
				(type default)
			)
			(layer "F.Fab")
		)
		(fp_line
			(start 0.120396 0.2794)
			(end -0.12065 0.2794)
			(stroke
				(width 0.1)
				(type default)
			)
			(layer "F.Fab")
		)
		(fp_line
			(start -0.12065 -0.2794)
			(end 0.12065 -0.2794)
			(stroke
				(width 0.1)
				(type default)
			)
			(layer "F.Fab")
		)
		(fp_line
			(start 0.12065 -0.2794)
			(end 0.12065 -0.3048)
			(stroke
				(width 0.1)
				(type default)
			)
			(layer "F.Fab")
		)
		(fp_line
			(start 0.12065 -0.3048)
			(end 0.67945 -0.3048)
			(stroke
				(width 0.1)
				(type default)
			)
			(layer "F.Fab")
		)
		(fp_line
			(start 0.67945 -0.3048)
			(end 0.67945 0.3048)
			(stroke
				(width 0.1)
				(type default)
			)
			(layer "F.Fab")
		)
		(fp_line
			(start -0.67945 -0.305054)
			(end -0.12065 -0.305054)
			(stroke
				(width 0.1)
				(type default)
			)
			(layer "F.Fab")
		)
		(fp_line
			(start -0.12065 -0.305054)
			(end -0.12065 -0.2794)
			(stroke
				(width 0.1)
				(type default)
			)
			(layer "F.Fab")
		)
		(pad "1" smd circle
			(at -0.40005 0 270)
			(size 0 0)
			(layers "F.Cu" "F.Mask" "F.Paste")
			(net "P3V3_AUX")
		)
		(pad "2" smd circle
			(at 0.40005 0 270)
			(size 0 0)
			(layers "F.Cu" "F.Mask" "F.Paste")
			(net "SMB_ALERT_HSC_R_N")
		)
	)
	(footprint ""
		(layer "F.Cu")
		(at 117.958362 -124.883926)
		(property "Reference" "PC303"
			(at 0 0 0)
			(layer "F.SilkS")
			(hide yes)
			(effects
				(font
					(size 1.27 1.27)
				)
			)
		)
		(property "Value" ""
			(at 0 0 0)
			(layer "F.Fab")
			(effects
				(font
					(size 1.27 1.27)
				)
			)
		)
		(duplicate_pad_numbers_are_jumpers no)
		(fp_line
			(start -0.7874 -0.4064)
			(end 0.7874 -0.4064)
			(stroke
				(width 0.1524)
				(type default)
			)
			(layer "F.SilkS")
		)
		(fp_line
			(start -0.7874 0.4064)
			(end -0.7874 -0.4064)
			(stroke
				(width 0.1524)
				(type default)
			)
			(layer "F.SilkS")
		)
		(fp_line
			(start 0.7874 -0.4064)
			(end 0.7874 0.4064)
			(stroke
				(width 0.1524)
				(type default)
			)
			(layer "F.SilkS")
		)
		(fp_line
			(start 0.7874 0.4064)
			(end -0.7874 0.4064)
			(stroke
				(width 0.1524)
				(type default)
			)
			(layer "F.SilkS")
		)
		(fp_line
			(start -0.67945 -0.305054)
			(end -0.12065 -0.305054)
			(stroke
				(width 0.1)
				(type default)
			)
			(layer "F.Fab")
		)
		(fp_line
			(start -0.67945 0.3048)
			(end -0.67945 -0.305054)
			(stroke
				(width 0.1)
				(type default)
			)
			(layer "F.Fab")
		)
		(fp_line
			(start -0.12065 -0.305054)
			(end -0.12065 -0.2794)
			(stroke
				(width 0.1)
				(type default)
			)
			(layer "F.Fab")
		)
		(fp_line
			(start -0.12065 -0.2794)
			(end 0.12065 -0.2794)
			(stroke
				(width 0.1)
				(type default)
			)
			(layer "F.Fab")
		)
		(fp_line
			(start -0.12065 0.2794)
			(end -0.12065 0.3048)
			(stroke
				(width 0.1)
				(type default)
			)
			(layer "F.Fab")
		)
		(fp_line
			(start -0.12065 0.3048)
			(end -0.67945 0.3048)
			(stroke
				(width 0.1)
				(type default)
			)
			(layer "F.Fab")
		)
		(fp_line
			(start 0.120396 0.2794)
			(end -0.12065 0.2794)
			(stroke
				(width 0.1)
				(type default)
			)
			(layer "F.Fab")
		)
		(fp_line
			(start 0.120396 0.3048)
			(end 0.120396 0.2794)
			(stroke
				(width 0.1)
				(type default)
			)
			(layer "F.Fab")
		)
		(fp_line
			(start 0.12065 -0.3048)
			(end 0.67945 -0.3048)
			(stroke
				(width 0.1)
				(type default)
			)
			(layer "F.Fab")
		)
		(fp_line
			(start 0.12065 -0.2794)
			(end 0.12065 -0.3048)
			(stroke
				(width 0.1)
				(type default)
			)
			(layer "F.Fab")
		)
		(fp_line
			(start 0.67945 -0.3048)
			(end 0.67945 0.3048)
			(stroke
				(width 0.1)
				(type default)
			)
			(layer "F.Fab")
		)
		(fp_line
			(start 0.67945 0.3048)
			(end 0.120396 0.3048)
			(stroke
				(width 0.1)
				(type default)
			)
			(layer "F.Fab")
		)
		(pad "1" smd circle
			(at -0.40005 0)
			(size 0 0)
			(layers "F.Cu" "F.Mask" "F.Paste")
			(net "P3V3_SS")
		)
		(pad "2" smd circle
			(at 0.40005 0)
			(size 0 0)
			(layers "F.Cu" "F.Mask" "F.Paste")
			(net "GND")
		)
	)
	(footprint ""
		(layer "F.Cu")
		(at 178.746404 -177.711862)
		(property "Reference" "U439"
			(at -1.58877 1.958594 0)
			(unlocked yes)
			(layer "F.SilkS")
			(effects
				(font
					(size 0.7874 0.5842)
					(thickness 0.1524)
				)
			)
		)
		(property "Value" ""
			(at 0 0 0)
			(layer "F.Fab")
			(effects
				(font
					(size 1.27 1.27)
				)
			)
		)
		(duplicate_pad_numbers_are_jumpers no)
		(fp_line
			(start -1.7272 1.1176)
			(end -1.7272 -1.1176)
			(stroke
				(width 0.1524)
				(type default)
			)
			(layer "F.SilkS")
		)
		(fp_line
			(start -0.254 -1.1176)
			(end -1.7272 -1.1176)
			(stroke
				(width 0.1524)
				(type default)
			)
			(layer "F.SilkS")
		)
		(fp_line
			(start 0 -0.7366)
			(end -0.254 -1.1176)
			(stroke
				(width 0.1524)
				(type default)
			)
			(layer "F.SilkS")
		)
		(fp_line
			(start 0.254 -1.1176)
			(end 0 -0.7366)
			(stroke
				(width 0.1524)
				(type default)
			)
			(layer "F.SilkS")
		)
		(fp_line
			(start 1.7272 -1.1176)
			(end 0.254 -1.1176)
			(stroke
				(width 0.1524)
				(type default)
			)
			(layer "F.SilkS")
		)
		(fp_line
			(start 1.7272 -1.1176)
			(end 1.7272 1.1176)
			(stroke
				(width 0.1524)
				(type default)
			)
			(layer "F.SilkS")
		)
		(fp_line
			(start 1.7272 1.1176)
			(end -1.7272 1.1176)
			(stroke
				(width 0.1524)
				(type default)
			)
			(layer "F.SilkS")
		)
		(fp_poly
			(pts
				(xy -1.9558 -0.649986) (xy -2.7178 -0.268986) (xy -2.7178 -1.030986)
			)
			(stroke
				(width 0)
				(type default)
			)
			(fill yes)
			(layer "F.SilkS")
		)
		(fp_line
			(start -1.5748 -1.1176)
			(end -1.5748 1.1176)
			(stroke
				(width 0.1)
				(type default)
			)
			(layer "F.Fab")
		)
		(fp_line
			(start -1.5748 1.1176)
			(end 1.5748 1.1176)
			(stroke
				(width 0.1)
				(type default)
			)
			(layer "F.Fab")
		)
		(fp_line
			(start 1.5748 -1.1176)
			(end -1.5748 -1.1176)
			(stroke
				(width 0.1)
				(type default)
			)
			(layer "F.Fab")
		)
		(fp_line
			(start 1.5748 1.1176)
			(end 1.5748 -1.1176)
			(stroke
				(width 0.1)
				(type default)
			)
			(layer "F.Fab")
		)
		(fp_poly
			(pts
				(xy -1.9558 -0.649986) (xy -2.7178 -0.268986) (xy -2.7178 -1.030986)
			)
			(stroke
				(width 0)
				(type default)
			)
			(fill yes)
			(layer "F.Fab")
		)
		(pad "1" smd rect
			(at -0.999998 -0.649986 270)
			(size 0.3556 1.1176)
			(layers "F.Cu" "F.Mask" "F.Paste")
			(net "NIC2_CLK_EN_R_N")
		)
		(pad "2" smd rect
			(at -0.999998 0 270)
			(size 0.3556 1.1176)
			(layers "F.Cu" "F.Mask" "F.Paste")
			(net "GND")
		)
		(pad "3" smd rect
			(at -0.999998 0.649986 270)
			(size 0.3556 1.1176)
			(layers "F.Cu" "F.Mask" "F.Paste")
			(net "NIC3_CLK_EN_R_N")
		)
		(pad "4" smd rect
			(at 0.999998 0.649986 270)
			(size 0.3556 1.1176)
			(layers "F.Cu" "F.Mask" "F.Paste")
			(net "NIC3_CLK_EN_BUF_N")
		)
		(pad "5" smd rect
			(at 0.999998 0 270)
			(size 0.3556 1.1176)
			(layers "F.Cu" "F.Mask" "F.Paste")
			(net "P3V3_AUX")
		)
		(pad "6" smd rect
			(at 0.999998 -0.649986 270)
			(size 0.3556 1.1176)
			(layers "F.Cu" "F.Mask" "F.Paste")
			(net "NIC2_CLK_EN_BUF_N")
		)
	)
)
